(kicad_pcb
	(version 20260206)
	(generator "pcbnew")
	(generator_version "10.0")
	(general
		(thickness 1.6)
		(legacy_teardrops no)
	)
	(paper "A4")
	(title_block
		(title "04192023_DAF0TMB3IC0_F0TG_MB_C_brd_V02_OCP.brd")
		(comment 1 "Grand Teton / footprints 11-15 of 8354")
	)
	(layers
		(0 "F.Cu" signal "TOP")
		(4 "In1.Cu" signal "GND")
		(6 "In2.Cu" signal "IN1")
		(8 "In3.Cu" signal "GND1")
		(10 "In4.Cu" signal "IN2")
		(12 "In5.Cu" signal "GND2")
		(14 "In6.Cu" signal "IN3")
		(16 "In7.Cu" signal "GND3")
		(18 "In8.Cu" signal "VCC")
		(20 "In9.Cu" signal "VCC1")
		(22 "In10.Cu" signal "GND4")
		(24 "In11.Cu" signal "IN4")
		(26 "In12.Cu" signal "GND5")
		(28 "In13.Cu" signal "IN5")
		(30 "In14.Cu" signal "GND6")
		(32 "In15.Cu" signal "IN6")
		(34 "In16.Cu" signal "GND7")
		(2 "B.Cu" signal "BOTTOM")
		(9 "F.Adhes" user "F.Adhesive")
		(11 "B.Adhes" user "B.Adhesive")
		(13 "F.Paste" user "Package Geometry/Pastemask Top")
		(15 "B.Paste" user "Package Geometry/Pastemask Bottom")
		(5 "F.SilkS" user "Ref Des/Silkscreen Top")
		(7 "B.SilkS" user "Ref Des/Silkscreen Bottom")
		(1 "F.Mask" user "Board Geometry/Soldermask Top")
		(3 "B.Mask" user "Board Geometry/Soldermask Bottom")
		(17 "Dwgs.User" user "User.Drawings")
		(19 "Cmts.User" user "User.Comments")
		(21 "Eco1.User" user "User.Eco1")
		(23 "Eco2.User" user "User.Eco2")
		(25 "Edge.Cuts" user "Board Geometry/Outline")
		(27 "Margin" user)
		(31 "F.CrtYd" user "Package Geometry/Place Bound Top")
		(29 "B.CrtYd" user "Package Geometry/Place Bound Bottom")
		(35 "F.Fab" user "Ref Des/Assembly Top")
		(33 "B.Fab" user "Ref Des/Assembly Bottom")
	)
	(footprint ""
		(layer "F.Cu")
		(at 391.291318 -74.375264 180)
		(property "Reference" "R1270"
			(at 0 0 180)
			(layer "F.SilkS")
			(hide yes)
			(effects
				(font
					(size 1.27 1.27)
				)
			)
		)
		(property "Value" ""
			(at 0 0 180)
			(layer "F.Fab")
			(effects
				(font
					(size 1.27 1.27)
				)
			)
		)
		(duplicate_pad_numbers_are_jumpers no)
		(fp_line
			(start 0.7874 0.4064)
			(end -0.7874 0.4064)
			(stroke
				(width 0.1524)
				(type default)
			)
			(layer "F.SilkS")
		)
		(fp_line
			(start 0.7874 -0.4064)
			(end 0.7874 0.4064)
			(stroke
				(width 0.1524)
				(type default)
			)
			(layer "F.SilkS")
		)
		(fp_line
			(start -0.7874 0.4064)
			(end -0.7874 -0.4064)
			(stroke
				(width 0.1524)
				(type default)
			)
			(layer "F.SilkS")
		)
		(fp_line
			(start -0.7874 -0.4064)
			(end 0.7874 -0.4064)
			(stroke
				(width 0.1524)
				(type default)
			)
			(layer "F.SilkS")
		)
		(fp_line
			(start 0.67945 0.3048)
			(end 0.120396 0.3048)
			(stroke
				(width 0.1)
				(type default)
			)
			(layer "F.Fab")
		)
		(fp_line
			(start 0.67945 -0.3048)
			(end 0.67945 0.3048)
			(stroke
				(width 0.1)
				(type default)
			)
			(layer "F.Fab")
		)
		(fp_line
			(start 0.12065 -0.2794)
			(end 0.12065 -0.3048)
			(stroke
				(width 0.1)
				(type default)
			)
			(layer "F.Fab")
		)
		(fp_line
			(start 0.12065 -0.3048)
			(end 0.67945 -0.3048)
			(stroke
				(width 0.1)
				(type default)
			)
			(layer "F.Fab")
		)
		(fp_line
			(start 0.120396 0.3048)
			(end 0.120396 0.2794)
			(stroke
				(width 0.1)
				(type default)
			)
			(layer "F.Fab")
		)
		(fp_line
			(start 0.120396 0.2794)
			(end -0.12065 0.2794)
			(stroke
				(width 0.1)
				(type default)
			)
			(layer "F.Fab")
		)
		(fp_line
			(start -0.12065 0.3048)
			(end -0.67945 0.3048)
			(stroke
				(width 0.1)
				(type default)
			)
			(layer "F.Fab")
		)
		(fp_line
			(start -0.12065 0.2794)
			(end -0.12065 0.3048)
			(stroke
				(width 0.1)
				(type default)
			)
			(layer "F.Fab")
		)
		(fp_line
			(start -0.12065 -0.2794)
			(end 0.12065 -0.2794)
			(stroke
				(width 0.1)
				(type default)
			)
			(layer "F.Fab")
		)
		(fp_line
			(start -0.12065 -0.305054)
			(end -0.12065 -0.2794)
			(stroke
				(width 0.1)
				(type default)
			)
			(layer "F.Fab")
		)
		(fp_line
			(start -0.67945 0.3048)
			(end -0.67945 -0.305054)
			(stroke
				(width 0.1)
				(type default)
			)
			(layer "F.Fab")
		)
		(fp_line
			(start -0.67945 -0.305054)
			(end -0.12065 -0.305054)
			(stroke
				(width 0.1)
				(type default)
			)
			(layer "F.Fab")
		)
		(pad "1" smd circle
			(at -0.40005 0 180)
			(size 0 0)
			(layers "F.Cu" "F.Mask" "F.Paste")
			(net "P12V_OCP_SFF_ADC_ALERT_R")
		)
		(pad "2" smd circle
			(at 0.40005 0 180)
			(size 0 0)
			(layers "F.Cu" "F.Mask" "F.Paste")
			(net "OCP_SFF_P3V3_P12V_ADC_R_ALERT")
		)
	)
	(footprint ""
		(layer "F.Cu")
		(at 522.584426 7.535926 -90)
		(property "Reference" "X8001"
			(at -1.918208 5.481574 0)
			(unlocked yes)
			(layer "F.SilkS")
			(effects
				(font
					(size 0.7874 0.5842)
					(thickness 0.1524)
				)
				(justify left)
			)
		)
		(property "Value" ""
			(at 0 0 270)
			(layer "F.Fab")
			(effects
				(font
					(size 1.27 1.27)
				)
			)
		)
		(property "Device Type" "TP_TDR_4P_FTS_TH-TP_TDR_4P_DIP,EMPTY,TP15"
			(at 1.30175 1.27 0)
			(unlocked yes)
			(layer "F.Fab")
			(hide yes)
			(effects
				(font
					(size 0.635 0.4064)
					(thickness 0.1524)
				)
			)
		)
		(property "User Part Number" "N_A"
			(at 1.30175 1.27 0)
			(unlocked yes)
			(layer "Cmts.User")
			(hide yes)
			(effects
				(font
					(size 0.635 0.4064)
					(thickness 0.1524)
				)
			)
		)
		(duplicate_pad_numbers_are_jumpers no)
		(fp_line
			(start 0 3.81)
			(end 2.54 3.81)
			(stroke
				(width 0.1524)
				(type default)
			)
			(layer "F.SilkS")
		)
		(fp_line
			(start 2.54 3.81)
			(end 2.54 3.6703)
			(stroke
				(width 0.1524)
				(type default)
			)
			(layer "F.SilkS")
		)
		(fp_line
			(start 0 3.175)
			(end 0 3.81)
			(stroke
				(width 0.1524)
				(type default)
			)
			(layer "F.SilkS")
		)
		(fp_line
			(start 2.54 1.4097)
			(end 2.54 1.1303)
			(stroke
				(width 0.1524)
				(type default)
			)
			(layer "F.SilkS")
		)
		(fp_line
			(start 0 0.635)
			(end 0 1.905)
			(stroke
				(width 0.1524)
				(type default)
			)
			(layer "F.SilkS")
		)
		(fp_line
			(start 2.54 -1.1303)
			(end 2.54 -1.27)
			(stroke
				(width 0.1524)
				(type default)
			)
			(layer "F.SilkS")
		)
		(fp_line
			(start 0 -1.27)
			(end 0 -0.635)
			(stroke
				(width 0.1524)
				(type default)
			)
			(layer "F.SilkS")
		)
		(fp_line
			(start 2.54 -1.27)
			(end 0 -1.27)
			(stroke
				(width 0.1524)
				(type default)
			)
			(layer "F.SilkS")
		)
		(fp_poly
			(pts
				(xy -2.285746 -0.762) (xy -0.761746 0) (xy -2.285746 0.762)
			)
			(stroke
				(width 0)
				(type default)
			)
			(fill yes)
			(layer "F.SilkS")
		)
		(fp_line
			(start 0 3.81)
			(end 2.54 3.81)
			(stroke
				(width 0.1)
				(type default)
			)
			(layer "F.Fab")
		)
		(fp_line
			(start 2.54 3.81)
			(end 2.54 -1.27)
			(stroke
				(width 0.1)
				(type default)
			)
			(layer "F.Fab")
		)
		(fp_line
			(start 0 -1.27)
			(end 0 3.81)
			(stroke
				(width 0.1)
				(type default)
			)
			(layer "F.Fab")
		)
		(fp_line
			(start 2.54 -1.27)
			(end 0 -1.27)
			(stroke
				(width 0.1)
				(type default)
			)
			(layer "F.Fab")
		)
		(fp_poly
			(pts
				(xy -0.761746 0) (xy -2.285746 -0.762) (xy -2.285746 0.762)
			)
			(stroke
				(width 0)
				(type default)
			)
			(fill yes)
			(layer "F.Fab")
		)
		(pad "1" thru_hole circle
			(at 0 0 270)
			(size 1.0033 1.0033)
			(drill 0.249936)
			(layers "*.Cu" "*.Mask")
			(remove_unused_layers no)
			(net "TDR_DIFF_85_TOP_DP")
			(clearance 0.10795)
			(thermal_gap 0.10795)
			(padstack
				(mode front_inner_back)
				(layer "Inner"
					(shape circle)
					(size 0.8001 0.8001)
					(clearance 0.1524)
				)
				(layer "B.Cu"
					(shape circle)
					(size 1.0033 1.0033)
					(clearance 0.10795)
				)
			)
		)
		(pad "2" thru_hole circle
			(at 2.54 0 270)
			(size 1.9939 1.9939)
			(drill 0.249936)
			(layers "*.Cu" "*.Mask")
			(remove_unused_layers no)
			(net "T1_GND")
			(clearance 0.10795)
			(thermal_gap 0.10795)
			(padstack
				(mode front_inner_back)
				(layer "Inner"
					(shape circle)
					(size 0.8001 0.8001)
					(clearance 0.1524)
				)
				(layer "B.Cu"
					(shape circle)
					(size 1.9939 1.9939)
					(clearance 0.10795)
				)
			)
		)
		(pad "3" thru_hole circle
			(at 2.54 2.54 270)
			(size 1.9939 1.9939)
			(drill 0.249936)
			(layers "*.Cu" "*.Mask")
			(remove_unused_layers no)
			(net "T1_GND")
			(clearance 0.10795)
			(thermal_gap 0.10795)
			(padstack
				(mode front_inner_back)
				(layer "Inner"
					(shape circle)
					(size 0.8001 0.8001)
					(clearance 0.1524)
				)
				(layer "B.Cu"
					(shape circle)
					(size 1.9939 1.9939)
					(clearance 0.10795)
				)
			)
		)
		(pad "4" thru_hole circle
			(at 0 2.54 270)
			(size 1.0033 1.0033)
			(drill 0.249936)
			(layers "*.Cu" "*.Mask")
			(remove_unused_layers no)
			(net "TDR_DIFF_85_TOP_DN")
			(clearance 0.10795)
			(thermal_gap 0.10795)
			(padstack
				(mode front_inner_back)
				(layer "Inner"
					(shape circle)
					(size 0.8001 0.8001)
					(clearance 0.1524)
				)
				(layer "B.Cu"
					(shape circle)
					(size 1.0033 1.0033)
					(clearance 0.10795)
				)
			)
		)
	)
	(footprint ""
		(layer "F.Cu")
		(at 75.705462 -39.675562)
		(property "Reference" "C2017"
			(at 0 0 0)
			(layer "F.SilkS")
			(hide yes)
			(effects
				(font
					(size 1.27 1.27)
				)
			)
		)
		(property "Value" ""
			(at 0 0 0)
			(layer "F.Fab")
			(effects
				(font
					(size 1.27 1.27)
				)
			)
		)
		(duplicate_pad_numbers_are_jumpers no)
		(fp_line
			(start -0.7874 -0.4064)
			(end 0.7874 -0.4064)
			(stroke
				(width 0.1524)
				(type default)
			)
			(layer "F.SilkS")
		)
		(fp_line
			(start -0.7874 0.4064)
			(end -0.7874 -0.4064)
			(stroke
				(width 0.1524)
				(type default)
			)
			(layer "F.SilkS")
		)
		(fp_line
			(start 0.7874 -0.4064)
			(end 0.7874 0.4064)
			(stroke
				(width 0.1524)
				(type default)
			)
			(layer "F.SilkS")
		)
		(fp_line
			(start 0.7874 0.4064)
			(end -0.7874 0.4064)
			(stroke
				(width 0.1524)
				(type default)
			)
			(layer "F.SilkS")
		)
		(fp_line
			(start -0.67945 -0.305054)
			(end -0.12065 -0.305054)
			(stroke
				(width 0.1)
				(type default)
			)
			(layer "F.Fab")
		)
		(fp_line
			(start -0.67945 0.3048)
			(end -0.67945 -0.305054)
			(stroke
				(width 0.1)
				(type default)
			)
			(layer "F.Fab")
		)
		(fp_line
			(start -0.12065 -0.305054)
			(end -0.12065 -0.2794)
			(stroke
				(width 0.1)
				(type default)
			)
			(layer "F.Fab")
		)
		(fp_line
			(start -0.12065 -0.2794)
			(end 0.12065 -0.2794)
			(stroke
				(width 0.1)
				(type default)
			)
			(layer "F.Fab")
		)
		(fp_line
			(start -0.12065 0.2794)
			(end -0.12065 0.3048)
			(stroke
				(width 0.1)
				(type default)
			)
			(layer "F.Fab")
		)
		(fp_line
			(start -0.12065 0.3048)
			(end -0.67945 0.3048)
			(stroke
				(width 0.1)
				(type default)
			)
			(layer "F.Fab")
		)
		(fp_line
			(start 0.120396 0.2794)
			(end -0.12065 0.2794)
			(stroke
				(width 0.1)
				(type default)
			)
			(layer "F.Fab")
		)
		(fp_line
			(start 0.120396 0.3048)
			(end 0.120396 0.2794)
			(stroke
				(width 0.1)
				(type default)
			)
			(layer "F.Fab")
		)
		(fp_line
			(start 0.12065 -0.3048)
			(end 0.67945 -0.3048)
			(stroke
				(width 0.1)
				(type default)
			)
			(layer "F.Fab")
		)
		(fp_line
			(start 0.12065 -0.2794)
			(end 0.12065 -0.3048)
			(stroke
				(width 0.1)
				(type default)
			)
			(layer "F.Fab")
		)
		(fp_line
			(start 0.67945 -0.3048)
			(end 0.67945 0.3048)
			(stroke
				(width 0.1)
				(type default)
			)
			(layer "F.Fab")
		)
		(fp_line
			(start 0.67945 0.3048)
			(end 0.120396 0.3048)
			(stroke
				(width 0.1)
				(type default)
			)
			(layer "F.Fab")
		)
		(pad "1" smd circle
			(at -0.40005 0)
			(size 0 0)
			(layers "F.Cu" "F.Mask" "F.Paste")
			(net "P3V3_OCP_V3_2_R")
		)
		(pad "2" smd circle
			(at 0.40005 0)
			(size 0 0)
			(layers "F.Cu" "F.Mask" "F.Paste")
			(net "GND")
		)
	)
	(footprint ""
		(layer "F.Cu")
		(at 86.487 -72.39)
		(property "Reference" "C1063"
			(at 0 0 0)
			(layer "F.SilkS")
			(hide yes)
			(effects
				(font
					(size 1.27 1.27)
				)
			)
		)
		(property "Value" ""
			(at 0 0 0)
			(layer "F.Fab")
			(effects
				(font
					(size 1.27 1.27)
				)
			)
		)
		(duplicate_pad_numbers_are_jumpers no)
		(fp_line
			(start -0.7874 -0.4064)
			(end 0.7874 -0.4064)
			(stroke
				(width 0.1524)
				(type default)
			)
			(layer "F.SilkS")
		)
		(fp_line
			(start -0.7874 0.4064)
			(end -0.7874 -0.4064)
			(stroke
				(width 0.1524)
				(type default)
			)
			(layer "F.SilkS")
		)
		(fp_line
			(start 0.7874 -0.4064)
			(end 0.7874 0.4064)
			(stroke
				(width 0.1524)
				(type default)
			)
			(layer "F.SilkS")
		)
		(fp_line
			(start 0.7874 0.4064)
			(end -0.7874 0.4064)
			(stroke
				(width 0.1524)
				(type default)
			)
			(layer "F.SilkS")
		)
		(fp_line
			(start -0.67945 -0.305054)
			(end -0.12065 -0.305054)
			(stroke
				(width 0.1)
				(type default)
			)
			(layer "F.Fab")
		)
		(fp_line
			(start -0.67945 0.3048)
			(end -0.67945 -0.305054)
			(stroke
				(width 0.1)
				(type default)
			)
			(layer "F.Fab")
		)
		(fp_line
			(start -0.12065 -0.305054)
			(end -0.12065 -0.2794)
			(stroke
				(width 0.1)
				(type default)
			)
			(layer "F.Fab")
		)
		(fp_line
			(start -0.12065 -0.2794)
			(end 0.12065 -0.2794)
			(stroke
				(width 0.1)
				(type default)
			)
			(layer "F.Fab")
		)
		(fp_line
			(start -0.12065 0.2794)
			(end -0.12065 0.3048)
			(stroke
				(width 0.1)
				(type default)
			)
			(layer "F.Fab")
		)
		(fp_line
			(start -0.12065 0.3048)
			(end -0.67945 0.3048)
			(stroke
				(width 0.1)
				(type default)
			)
			(layer "F.Fab")
		)
		(fp_line
			(start 0.120396 0.2794)
			(end -0.12065 0.2794)
			(stroke
				(width 0.1)
				(type default)
			)
			(layer "F.Fab")
		)
		(fp_line
			(start 0.120396 0.3048)
			(end 0.120396 0.2794)
			(stroke
				(width 0.1)
				(type default)
			)
			(layer "F.Fab")
		)
		(fp_line
			(start 0.12065 -0.3048)
			(end 0.67945 -0.3048)
			(stroke
				(width 0.1)
				(type default)
			)
			(layer "F.Fab")
		)
		(fp_line
			(start 0.12065 -0.2794)
			(end 0.12065 -0.3048)
			(stroke
				(width 0.1)
				(type default)
			)
			(layer "F.Fab")
		)
		(fp_line
			(start 0.67945 -0.3048)
			(end 0.67945 0.3048)
			(stroke
				(width 0.1)
				(type default)
			)
			(layer "F.Fab")
		)
		(fp_line
			(start 0.67945 0.3048)
			(end 0.120396 0.3048)
			(stroke
				(width 0.1)
				(type default)
			)
			(layer "F.Fab")
		)
		(pad "1" smd circle
			(at -0.40005 0)
			(size 0 0)
			(layers "F.Cu" "F.Mask" "F.Paste")
			(net "P3V3_AUX")
		)
		(pad "2" smd circle
			(at 0.40005 0)
			(size 0 0)
			(layers "F.Cu" "F.Mask" "F.Paste")
			(net "GND")
		)
	)
	(footprint ""
		(layer "F.Cu")
		(at 273.35734 -122.880628 180)
		(property "Reference" "R4269"
			(at 0 0 180)
			(layer "F.SilkS")
			(hide yes)
			(effects
				(font
					(size 1.27 1.27)
				)
			)
		)
		(property "Value" ""
			(at 0 0 180)
			(layer "F.Fab")
			(effects
				(font
					(size 1.27 1.27)
				)
			)
		)
		(duplicate_pad_numbers_are_jumpers no)
		(fp_line
			(start 0.7874 0.4064)
			(end -0.7874 0.4064)
			(stroke
				(width 0.1524)
				(type default)
			)
			(layer "F.SilkS")
		)
		(fp_line
			(start 0.7874 -0.4064)
			(end 0.7874 0.4064)
			(stroke
				(width 0.1524)
				(type default)
			)
			(layer "F.SilkS")
		)
		(fp_line
			(start -0.7874 0.4064)
			(end -0.7874 -0.4064)
			(stroke
				(width 0.1524)
				(type default)
			)
			(layer "F.SilkS")
		)
		(fp_line
			(start -0.7874 -0.4064)
			(end 0.7874 -0.4064)
			(stroke
				(width 0.1524)
				(type default)
			)
			(layer "F.SilkS")
		)
		(fp_line
			(start 0.67945 0.3048)
			(end 0.120396 0.3048)
			(stroke
				(width 0.1)
				(type default)
			)
			(layer "F.Fab")
		)
		(fp_line
			(start 0.67945 -0.3048)
			(end 0.67945 0.3048)
			(stroke
				(width 0.1)
				(type default)
			)
			(layer "F.Fab")
		)
		(fp_line
			(start 0.12065 -0.2794)
			(end 0.12065 -0.3048)
			(stroke
				(width 0.1)
				(type default)
			)
			(layer "F.Fab")
		)
		(fp_line
			(start 0.12065 -0.3048)
			(end 0.67945 -0.3048)
			(stroke
				(width 0.1)
				(type default)
			)
			(layer "F.Fab")
		)
		(fp_line
			(start 0.120396 0.3048)
			(end 0.120396 0.2794)
			(stroke
				(width 0.1)
				(type default)
			)
			(layer "F.Fab")
		)
		(fp_line
			(start 0.120396 0.2794)
			(end -0.12065 0.2794)
			(stroke
				(width 0.1)
				(type default)
			)
			(layer "F.Fab")
		)
		(fp_line
			(start -0.12065 0.3048)
			(end -0.67945 0.3048)
			(stroke
				(width 0.1)
				(type default)
			)
			(layer "F.Fab")
		)
		(fp_line
			(start -0.12065 0.2794)
			(end -0.12065 0.3048)
			(stroke
				(width 0.1)
				(type default)
			)
			(layer "F.Fab")
		)
		(fp_line
			(start -0.12065 -0.2794)
			(end 0.12065 -0.2794)
			(stroke
				(width 0.1)
				(type default)
			)
			(layer "F.Fab")
		)
		(fp_line
			(start -0.12065 -0.305054)
			(end -0.12065 -0.2794)
			(stroke
				(width 0.1)
				(type default)
			)
			(layer "F.Fab")
		)
		(fp_line
			(start -0.67945 0.3048)
			(end -0.67945 -0.305054)
			(stroke
				(width 0.1)
				(type default)
			)
			(layer "F.Fab")
		)
		(fp_line
			(start -0.67945 -0.305054)
			(end -0.12065 -0.305054)
			(stroke
				(width 0.1)
				(type default)
			)
			(layer "F.Fab")
		)
		(pad "1" smd circle
			(at -0.40005 0 180)
			(size 0 0)
			(layers "F.Cu" "F.Mask" "F.Paste")
			(net "P3V3_AUX")
		)
		(pad "2" smd circle
			(at 0.40005 0 180)
			(size 0 0)
			(layers "F.Cu" "F.Mask" "F.Paste")
			(net "SMB_VR_SENSOR_3V3AUX_SCL")
		)
	)
)
